# Bryce Canyon_ME BOM MP.xlsx — EXTERNAL CABLE (bom)
| Wistron P/N | Wistron Description | Description | Vendor | Attachment |
| B50.01109.0001 | C.A. HDMSAS 12G/MSAS 6G,1M,APH | 6G-> 12G cable, 1M | Amphenol | CNBCECBF399_RevB |
| B50.0110A.0001 | C.A. HDMSAS 12G/MSAS 6G,1.5M,APH | 6G-> 12G cable, 1.5M |  |  |
| B50.0110B.0001 | C.A. HDMSAS 12G/MSAS 6G,2M,APH | 6G-> 12G cable, 2M |  |  |
| B50.0110X.0001 | C.A. HDMSAS 12G/MSAS 6G,2.5M,APH | 6G-> 12G cable, 2.5M |  |  |
| B50.0110C.0001 | C.A. HDMSAS 12G/MSAS 6G,3M,APH | 6G-> 12G cable, 3M |  |  |
| B50.0110H.0001 | C.A. HDMSAS 12G/MSAS 6G,1M,MOLEX | 6G-> 12G cable, 1M | Molex | SD-111068-3200_1_F[1] |
| B50.0110I.0001 | C.A. HDMSAS 12G/MSAS 6G,2M,MOLEX | 6G-> 12G cable, 2M |  |  |
| B50.0110J.0001 | C.A. HDMSAS 12G/MSAS 6G,3M,MOLEX | 6G-> 12G cable, 3M |  |  |
| B50.0110D.0001 | C.A. HDMSAS 12G/(2)HDMSAS 12G,1M,APH | Y cable, 1M | Amphenol | C-NBCTCB-F399 - Sheet1 |
| B50.0110E.0001 | C.A. HDMSAS 12G/(2)HDMSAS 12G,1.5M,APH | Y cable, 1.5M |  |  |
| B50.0110F.0001 | C.A. HDMSAS 12G/(2)HDMSAS 12G,2M,APH | Y cable, 2M |  |  |
| B50.0110G.0001 | C.A. HDMSAS 12G/(2)HDMSAS 12G,3M,APH | Y cable, 3M |  |  |
| B50.0110K.0001 | C.A. HDMSAS/(2)HDMSAS,1M,MOLEX | Y cable, 1M | Molex |  |
| B50.0110L.0001 | C.A. HDMSAS/(2)HDMSAS,1.5M,MOLEX | Y cable, 1.5M |  |  |
| B50.0110M.0001 | C.A. HDMSAS/(2)HDMSAS,2M,MOLEX | Y cable, 2M |  |  |
| B50.0110N.0001 | C.A. HDMSAS/(2)HDMSAS,3M,MOLEX | Y cable, 3M |  |  |
